(kicad_pcb
	(version 20260206)
	(generator "pcbnew")
	(generator_version "10.0")
	(general
		(thickness 1.6)
		(legacy_teardrops no)
	)
	(paper "A4")
	(title_block
		(title "v1-chassis-manager — T6M_CM_d_v01_1031_1645.brd")
		(comment 1 "Open CloudServer (Microsoft) / footprints 1485-1495 of 2512")
	)
	(layers
		(0 "F.Cu" signal "TOP")
		(4 "In1.Cu" signal "GND1")
		(6 "In2.Cu" signal "IN1")
		(8 "In3.Cu" signal "VCC1")
		(10 "In4.Cu" signal "VCC2")
		(12 "In5.Cu" signal "GND2")
		(14 "In6.Cu" signal "IN2")
		(16 "In7.Cu" signal "IN3")
		(18 "In8.Cu" signal "GND3")
		(2 "B.Cu" signal "BOTTOM")
		(9 "F.Adhes" user "F.Adhesive")
		(11 "B.Adhes" user "B.Adhesive")
		(13 "F.Paste" user "Package Geometry/Pastemask Top")
		(15 "B.Paste" user "Package Geometry/Pastemask Bottom")
		(5 "F.SilkS" user "Ref Des/Silkscreen Top")
		(7 "B.SilkS" user "Ref Des/Silkscreen Bottom")
		(1 "F.Mask" user "Board Geometry/Soldermask Top")
		(3 "B.Mask" user "Board Geometry/Soldermask Bottom")
		(17 "Dwgs.User" user "User.Drawings")
		(19 "Cmts.User" user "User.Comments")
		(21 "Eco1.User" user "User.Eco1")
		(23 "Eco2.User" user "User.Eco2")
		(25 "Edge.Cuts" user "Board Geometry/Outline")
		(27 "Margin" user)
		(31 "F.CrtYd" user "Package Geometry/Place Bound Top")
		(29 "B.CrtYd" user "Package Geometry/Place Bound Bottom")
		(35 "F.Fab" user "Ref Des/Assembly Top")
		(33 "B.Fab" user "Ref Des/Assembly Bottom")
	)
	(footprint ""
		(layer "F.Cu")
		(at 148.122894 -167.093392 180)
		(property "Reference" "C907"
			(at 1.508252 0.927862 0)
			(unlocked yes)
			(layer "F.SilkS")
			(effects
				(font
					(size 0.7874 0.5842)
					(thickness 0.1524)
				)
				(justify left)
			)
		)
		(property "Value" ""
			(at 0 0 180)
			(layer "F.Fab")
			(effects
				(font
					(size 1.27 1.27)
				)
			)
		)
		(duplicate_pad_numbers_are_jumpers no)
		(fp_line
			(start 0.7874 0.4064)
			(end -0.7874 0.4064)
			(stroke
				(width 0.1524)
				(type default)
			)
			(layer "F.SilkS")
		)
		(fp_line
			(start 0.7874 -0.4064)
			(end 0.7874 0.4064)
			(stroke
				(width 0.1524)
				(type default)
			)
			(layer "F.SilkS")
		)
		(fp_line
			(start 0 0.381)
			(end 0 -0.381)
			(stroke
				(width 0.1524)
				(type default)
			)
			(layer "F.SilkS")
		)
		(fp_line
			(start -0.7874 0.4064)
			(end -0.7874 -0.4064)
			(stroke
				(width 0.1524)
				(type default)
			)
			(layer "F.SilkS")
		)
		(fp_line
			(start -0.7874 -0.4064)
			(end 0.7874 -0.4064)
			(stroke
				(width 0.1524)
				(type default)
			)
			(layer "F.SilkS")
		)
		(fp_poly
			(pts
				(xy -0.5334 0.254) (xy -0.635 0.254) (xy -0.635 0.2286) (xy -0.635 -0.254) (xy -0.5334 -0.254) (xy -0.5334 -0.2794)
				(xy 0.5334 -0.2794) (xy 0.5334 -0.254) (xy 0.635 -0.254) (xy 0.635 0.254) (xy 0.5334 0.254) (xy 0.5334 0.2794)
				(xy -0.508 0.2794) (xy -0.5334 0.2794)
			)
			(stroke
				(width 0)
				(type default)
			)
			(fill no)
			(layer "F.CrtYd")
		)
		(pad "1" smd rect
			(at 0.40005 0 180)
			(size 0.4572 0.508)
			(layers "F.Cu" "F.Mask" "F.Paste")
			(net "P3V3_NODE1")
		)
		(pad "2" smd rect
			(at -0.40005 0 180)
			(size 0.4572 0.508)
			(layers "F.Cu" "F.Mask" "F.Paste")
			(net "GND")
		)
	)
	(footprint ""
		(layer "F.Cu")
		(at 128.517904 -162.25012)
		(property "Reference" "R669"
			(at -61.67882 109.81436 0)
			(unlocked yes)
			(layer "F.SilkS")
			(effects
				(font
					(size 0.7874 0.5842)
					(thickness 0.1524)
				)
				(justify left)
			)
		)
		(property "Value" ""
			(at 0 0 0)
			(layer "F.Fab")
			(effects
				(font
					(size 1.27 1.27)
				)
			)
		)
		(duplicate_pad_numbers_are_jumpers no)
		(fp_line
			(start -0.7874 -0.4064)
			(end 0.7874 -0.4064)
			(stroke
				(width 0.1524)
				(type default)
			)
			(layer "F.SilkS")
		)
		(fp_line
			(start -0.7874 0.4064)
			(end -0.7874 -0.4064)
			(stroke
				(width 0.1524)
				(type default)
			)
			(layer "F.SilkS")
		)
		(fp_line
			(start 0.7874 -0.4064)
			(end 0.7874 0.4064)
			(stroke
				(width 0.1524)
				(type default)
			)
			(layer "F.SilkS")
		)
		(fp_line
			(start 0.7874 0.4064)
			(end -0.7874 0.4064)
			(stroke
				(width 0.1524)
				(type default)
			)
			(layer "F.SilkS")
		)
		(fp_poly
			(pts
				(xy -0.508 0.2794) (xy -0.508 0.2286) (xy -0.635 0.2286) (xy -0.635 -0.254) (xy -0.5334 -0.254)
				(xy -0.5334 -0.2794) (xy 0.5334 -0.2794) (xy 0.5334 -0.254) (xy 0.635 -0.254) (xy 0.635 0.254) (xy 0.5334 0.254)
				(xy 0.5334 0.2794)
			)
			(stroke
				(width 0)
				(type default)
			)
			(fill no)
			(layer "F.CrtYd")
		)
		(pad "1" smd rect
			(at 0.40005 0)
			(size 0.4572 0.508)
			(layers "F.Cu" "F.Mask" "F.Paste")
			(net "P3V3_NODE1")
		)
		(pad "2" smd rect
			(at -0.40005 0)
			(size 0.4572 0.508)
			(layers "F.Cu" "F.Mask" "F.Paste")
			(net "I2C_PSU3_SCL_MOS")
		)
	)
	(footprint ""
		(layer "F.Cu")
		(at 105.191814 -104.85882 180)
		(property "Reference" "PC123"
			(at 6.020054 0.747014 0)
			(unlocked yes)
			(layer "F.SilkS")
			(effects
				(font
					(size 0.7874 0.5842)
					(thickness 0.1524)
				)
				(justify left)
			)
		)
		(property "Value" ""
			(at 0 0 180)
			(layer "F.Fab")
			(effects
				(font
					(size 1.27 1.27)
				)
			)
		)
		(duplicate_pad_numbers_are_jumpers no)
		(fp_line
			(start 1.905 0.8636)
			(end -1.905 0.8636)
			(stroke
				(width 0.1524)
				(type default)
			)
			(layer "F.SilkS")
		)
		(fp_line
			(start 1.905 -0.8636)
			(end 1.905 0.8636)
			(stroke
				(width 0.1524)
				(type default)
			)
			(layer "F.SilkS")
		)
		(fp_line
			(start 0 0.8382)
			(end 0 -0.8382)
			(stroke
				(width 0.1524)
				(type default)
			)
			(layer "F.SilkS")
		)
		(fp_line
			(start -1.905 0.8636)
			(end -1.905 -0.8636)
			(stroke
				(width 0.1524)
				(type default)
			)
			(layer "F.SilkS")
		)
		(fp_line
			(start -1.905 -0.8636)
			(end 1.905 -0.8636)
			(stroke
				(width 0.1524)
				(type default)
			)
			(layer "F.SilkS")
		)
		(fp_rect
			(start -1.524 0.7366)
			(end 1.524 -0.7366)
			(stroke
				(width 0)
				(type default)
			)
			(fill no)
			(layer "F.CrtYd")
		)
		(pad "1" smd rect
			(at 0.94996 0 180)
			(size 1.1176 1.3716)
			(layers "F.Cu" "F.Mask" "F.Paste")
			(net "GND")
		)
		(pad "2" smd rect
			(at -0.94996 0 180)
			(size 1.1176 1.3716)
			(layers "F.Cu" "F.Mask" "F.Paste")
			(net "PV_VCCP_NODE1")
		)
	)
	(footprint ""
		(layer "F.Cu")
		(at 144.916652 -137.36955 180)
		(property "Reference" "R263"
			(at 0.990346 -17.103344 0)
			(unlocked yes)
			(layer "F.SilkS")
			(effects
				(font
					(size 0.7874 0.5842)
					(thickness 0.1524)
				)
				(justify left)
			)
		)
		(property "Value" ""
			(at 0 0 180)
			(layer "F.Fab")
			(effects
				(font
					(size 1.27 1.27)
				)
			)
		)
		(duplicate_pad_numbers_are_jumpers no)
		(fp_line
			(start 0.7874 0.4064)
			(end -0.7874 0.4064)
			(stroke
				(width 0.1524)
				(type default)
			)
			(layer "F.SilkS")
		)
		(fp_line
			(start 0.7874 -0.4064)
			(end 0.7874 0.4064)
			(stroke
				(width 0.1524)
				(type default)
			)
			(layer "F.SilkS")
		)
		(fp_line
			(start -0.7874 0.4064)
			(end -0.7874 -0.4064)
			(stroke
				(width 0.1524)
				(type default)
			)
			(layer "F.SilkS")
		)
		(fp_line
			(start -0.7874 -0.4064)
			(end 0.7874 -0.4064)
			(stroke
				(width 0.1524)
				(type default)
			)
			(layer "F.SilkS")
		)
		(fp_poly
			(pts
				(xy -0.508 0.2794) (xy -0.508 0.2286) (xy -0.635 0.2286) (xy -0.635 -0.254) (xy -0.5334 -0.254)
				(xy -0.5334 -0.2794) (xy 0.5334 -0.2794) (xy 0.5334 -0.254) (xy 0.635 -0.254) (xy 0.635 0.254) (xy 0.5334 0.254)
				(xy 0.5334 0.2794)
			)
			(stroke
				(width 0)
				(type default)
			)
			(fill no)
			(layer "F.CrtYd")
		)
		(pad "1" smd rect
			(at 0.40005 0 180)
			(size 0.4572 0.508)
			(layers "F.Cu" "F.Mask" "F.Paste")
			(net "PCIE_SW_WAKE_N")
		)
		(pad "2" smd rect
			(at -0.40005 0 180)
			(size 0.4572 0.508)
			(layers "F.Cu" "F.Mask" "F.Paste")
			(net "IRQ_LVC3_CPU_NODE1_WAKE_L")
		)
	)
	(footprint ""
		(layer "F.Cu")
		(at 52.81676 -188.126624 90)
		(property "Reference" "R845"
			(at 4.548886 0.205232 90)
			(unlocked yes)
			(layer "F.SilkS")
			(effects
				(font
					(size 0.7874 0.5842)
					(thickness 0.1524)
				)
				(justify left)
			)
		)
		(property "Value" ""
			(at 0 0 90)
			(layer "F.Fab")
			(effects
				(font
					(size 1.27 1.27)
				)
			)
		)
		(duplicate_pad_numbers_are_jumpers no)
		(fp_line
			(start 0.7874 -0.4064)
			(end 0.7874 0.4064)
			(stroke
				(width 0.1524)
				(type default)
			)
			(layer "F.SilkS")
		)
		(fp_line
			(start -0.7874 -0.4064)
			(end 0.7874 -0.4064)
			(stroke
				(width 0.1524)
				(type default)
			)
			(layer "F.SilkS")
		)
		(fp_line
			(start 0.7874 0.4064)
			(end -0.7874 0.4064)
			(stroke
				(width 0.1524)
				(type default)
			)
			(layer "F.SilkS")
		)
		(fp_line
			(start -0.7874 0.4064)
			(end -0.7874 -0.4064)
			(stroke
				(width 0.1524)
				(type default)
			)
			(layer "F.SilkS")
		)
		(fp_poly
			(pts
				(xy -0.508 0.2794) (xy -0.508 0.2286) (xy -0.635 0.2286) (xy -0.635 -0.254) (xy -0.5334 -0.254)
				(xy -0.5334 -0.2794) (xy 0.5334 -0.2794) (xy 0.5334 -0.254) (xy 0.635 -0.254) (xy 0.635 0.254) (xy 0.5334 0.254)
				(xy 0.5334 0.2794)
			)
			(stroke
				(width 0)
				(type default)
			)
			(fill no)
			(layer "F.CrtYd")
		)
		(pad "1" smd rect
			(at 0.40005 0 90)
			(size 0.4572 0.508)
			(layers "F.Cu" "F.Mask" "F.Paste")
			(net "PSU1_AC_OK_R")
		)
		(pad "2" smd rect
			(at -0.40005 0 90)
			(size 0.4572 0.508)
			(layers "F.Cu" "F.Mask" "F.Paste")
			(net "GND")
		)
	)
	(footprint ""
		(layer "F.Cu")
		(at 73.148698 -17.679416 90)
		(property "Reference" "C151"
			(at -4.60629 6.316472 90)
			(unlocked yes)
			(layer "F.SilkS")
			(effects
				(font
					(size 0.7874 0.5842)
					(thickness 0.1524)
				)
				(justify left)
			)
		)
		(property "Value" ""
			(at 0 0 90)
			(layer "F.Fab")
			(effects
				(font
					(size 1.27 1.27)
				)
			)
		)
		(duplicate_pad_numbers_are_jumpers no)
		(fp_line
			(start 0.7874 -0.4064)
			(end 0.7874 0.4064)
			(stroke
				(width 0.1524)
				(type default)
			)
			(layer "F.SilkS")
		)
		(fp_line
			(start -0.7874 -0.4064)
			(end 0.7874 -0.4064)
			(stroke
				(width 0.1524)
				(type default)
			)
			(layer "F.SilkS")
		)
		(fp_line
			(start 0 0.381)
			(end 0 -0.381)
			(stroke
				(width 0.1524)
				(type default)
			)
			(layer "F.SilkS")
		)
		(fp_line
			(start 0.7874 0.4064)
			(end -0.7874 0.4064)
			(stroke
				(width 0.1524)
				(type default)
			)
			(layer "F.SilkS")
		)
		(fp_line
			(start -0.7874 0.4064)
			(end -0.7874 -0.4064)
			(stroke
				(width 0.1524)
				(type default)
			)
			(layer "F.SilkS")
		)
		(fp_poly
			(pts
				(xy -0.5334 0.254) (xy -0.635 0.254) (xy -0.635 0.2286) (xy -0.635 -0.254) (xy -0.5334 -0.254) (xy -0.5334 -0.2794)
				(xy 0.5334 -0.2794) (xy 0.5334 -0.254) (xy 0.635 -0.254) (xy 0.635 0.254) (xy 0.5334 0.254) (xy 0.5334 0.2794)
				(xy -0.508 0.2794) (xy -0.5334 0.2794)
			)
			(stroke
				(width 0)
				(type default)
			)
			(fill no)
			(layer "F.CrtYd")
		)
		(pad "1" smd rect
			(at 0.40005 0 90)
			(size 0.4572 0.508)
			(layers "F.Cu" "F.Mask" "F.Paste")
			(net "PV_VDDR_NODE1")
		)
		(pad "2" smd rect
			(at -0.40005 0 90)
			(size 0.4572 0.508)
			(layers "F.Cu" "F.Mask" "F.Paste")
			(net "GND")
		)
	)
	(footprint ""
		(layer "F.Cu")
		(at 123.70816 -166.523416)
		(property "Reference" "R623"
			(at 30.075378 46.17339 0)
			(unlocked yes)
			(layer "F.SilkS")
			(effects
				(font
					(size 0.7874 0.5842)
					(thickness 0.1524)
				)
				(justify left)
			)
		)
		(property "Value" ""
			(at 0 0 0)
			(layer "F.Fab")
			(effects
				(font
					(size 1.27 1.27)
				)
			)
		)
		(duplicate_pad_numbers_are_jumpers no)
		(fp_line
			(start -0.7874 -0.4064)
			(end 0.7874 -0.4064)
			(stroke
				(width 0.1524)
				(type default)
			)
			(layer "F.SilkS")
		)
		(fp_line
			(start -0.7874 0.4064)
			(end -0.7874 -0.4064)
			(stroke
				(width 0.1524)
				(type default)
			)
			(layer "F.SilkS")
		)
		(fp_line
			(start 0.7874 -0.4064)
			(end 0.7874 0.4064)
			(stroke
				(width 0.1524)
				(type default)
			)
			(layer "F.SilkS")
		)
		(fp_line
			(start 0.7874 0.4064)
			(end -0.7874 0.4064)
			(stroke
				(width 0.1524)
				(type default)
			)
			(layer "F.SilkS")
		)
		(fp_poly
			(pts
				(xy -0.508 0.2794) (xy -0.508 0.2286) (xy -0.635 0.2286) (xy -0.635 -0.254) (xy -0.5334 -0.254)
				(xy -0.5334 -0.2794) (xy 0.5334 -0.2794) (xy 0.5334 -0.254) (xy 0.635 -0.254) (xy 0.635 0.254) (xy 0.5334 0.254)
				(xy 0.5334 0.2794)
			)
			(stroke
				(width 0)
				(type default)
			)
			(fill no)
			(layer "F.CrtYd")
		)
		(pad "1" smd rect
			(at 0.40005 0)
			(size 0.4572 0.508)
			(layers "F.Cu" "F.Mask" "F.Paste")
			(net "CPLD_WDT1")
		)
		(pad "2" smd rect
			(at -0.40005 0)
			(size 0.4572 0.508)
			(layers "F.Cu" "F.Mask" "F.Paste")
			(net "CPLD_WDT1_R")
		)
	)
	(footprint ""
		(layer "F.Cu")
		(at 57.973468 -118.960646 -90)
		(property "Reference" "R343"
			(at 5.19049 -1.117092 90)
			(unlocked yes)
			(layer "F.SilkS")
			(effects
				(font
					(size 0.7874 0.5842)
					(thickness 0.1524)
				)
				(justify left)
			)
		)
		(property "Value" ""
			(at 0 0 270)
			(layer "F.Fab")
			(effects
				(font
					(size 1.27 1.27)
				)
			)
		)
		(duplicate_pad_numbers_are_jumpers no)
		(fp_line
			(start -0.7874 0.4064)
			(end -0.7874 -0.4064)
			(stroke
				(width 0.1524)
				(type default)
			)
			(layer "F.SilkS")
		)
		(fp_line
			(start 0.7874 0.4064)
			(end -0.7874 0.4064)
			(stroke
				(width 0.1524)
				(type default)
			)
			(layer "F.SilkS")
		)
		(fp_line
			(start -0.7874 -0.4064)
			(end 0.7874 -0.4064)
			(stroke
				(width 0.1524)
				(type default)
			)
			(layer "F.SilkS")
		)
		(fp_line
			(start 0.7874 -0.4064)
			(end 0.7874 0.4064)
			(stroke
				(width 0.1524)
				(type default)
			)
			(layer "F.SilkS")
		)
		(fp_poly
			(pts
				(xy -0.508 0.2794) (xy -0.508 0.2286) (xy -0.635 0.2286) (xy -0.635 -0.254) (xy -0.5334 -0.254)
				(xy -0.5334 -0.2794) (xy 0.5334 -0.2794) (xy 0.5334 -0.254) (xy 0.635 -0.254) (xy 0.635 0.254) (xy 0.5334 0.254)
				(xy 0.5334 0.2794)
			)
			(stroke
				(width 0)
				(type default)
			)
			(fill no)
			(layer "F.CrtYd")
		)
		(pad "1" smd rect
			(at 0.40005 0 270)
			(size 0.4572 0.508)
			(layers "F.Cu" "F.Mask" "F.Paste")
			(net "P3V3_NODE1")
		)
		(pad "2" smd rect
			(at -0.40005 0 270)
			(size 0.4572 0.508)
			(layers "F.Cu" "F.Mask" "F.Paste")
			(net "BMC_ROMD3")
		)
	)
	(footprint ""
		(layer "F.Cu")
		(at 80.99552 -158.242508 90)
		(property "Reference" "PR1"
			(at -0.945388 4.343146 90)
			(unlocked yes)
			(layer "F.SilkS")
			(effects
				(font
					(size 0.7874 0.5842)
					(thickness 0.1524)
				)
				(justify left)
			)
		)
		(property "Value" ""
			(at 0 0 90)
			(layer "F.Fab")
			(effects
				(font
					(size 1.27 1.27)
				)
			)
		)
		(duplicate_pad_numbers_are_jumpers no)
		(fp_line
			(start 0.7874 -0.4064)
			(end 0.7874 0.4064)
			(stroke
				(width 0.1524)
				(type default)
			)
			(layer "F.SilkS")
		)
		(fp_line
			(start -0.7874 -0.4064)
			(end 0.7874 -0.4064)
			(stroke
				(width 0.1524)
				(type default)
			)
			(layer "F.SilkS")
		)
		(fp_line
			(start 0.7874 0.4064)
			(end -0.7874 0.4064)
			(stroke
				(width 0.1524)
				(type default)
			)
			(layer "F.SilkS")
		)
		(fp_line
			(start -0.7874 0.4064)
			(end -0.7874 -0.4064)
			(stroke
				(width 0.1524)
				(type default)
			)
			(layer "F.SilkS")
		)
		(fp_poly
			(pts
				(xy -0.508 0.2794) (xy -0.508 0.2286) (xy -0.635 0.2286) (xy -0.635 -0.254) (xy -0.5334 -0.254)
				(xy -0.5334 -0.2794) (xy 0.5334 -0.2794) (xy 0.5334 -0.254) (xy 0.635 -0.254) (xy 0.635 0.254) (xy 0.5334 0.254)
				(xy 0.5334 0.2794)
			)
			(stroke
				(width 0)
				(type default)
			)
			(fill no)
			(layer "F.CrtYd")
		)
		(pad "1" smd rect
			(at 0.40005 0 90)
			(size 0.4572 0.508)
			(layers "F.Cu" "F.Mask" "F.Paste")
			(net "P5V_STB_NODE1_VREG5")
		)
		(pad "2" smd rect
			(at -0.40005 0 90)
			(size 0.4572 0.508)
			(layers "F.Cu" "F.Mask" "F.Paste")
			(net "PWRGD_NODE1_P5V_STB_PG")
		)
	)
	(footprint ""
		(layer "F.Cu")
		(at 134.35457 -26.569416 -90)
		(property "Reference" "R1148"
			(at 5.325618 -0.241808 90)
			(unlocked yes)
			(layer "F.SilkS")
			(effects
				(font
					(size 0.7874 0.5842)
					(thickness 0.1524)
				)
				(justify left)
			)
		)
		(property "Value" ""
			(at 0 0 270)
			(layer "F.Fab")
			(effects
				(font
					(size 1.27 1.27)
				)
			)
		)
		(duplicate_pad_numbers_are_jumpers no)
		(fp_line
			(start -0.7874 0.4064)
			(end -0.7874 -0.4064)
			(stroke
				(width 0.1524)
				(type default)
			)
			(layer "F.SilkS")
		)
		(fp_line
			(start 0.7874 0.4064)
			(end -0.7874 0.4064)
			(stroke
				(width 0.1524)
				(type default)
			)
			(layer "F.SilkS")
		)
		(fp_line
			(start -0.7874 -0.4064)
			(end 0.7874 -0.4064)
			(stroke
				(width 0.1524)
				(type default)
			)
			(layer "F.SilkS")
		)
		(fp_line
			(start 0.7874 -0.4064)
			(end 0.7874 0.4064)
			(stroke
				(width 0.1524)
				(type default)
			)
			(layer "F.SilkS")
		)
		(fp_poly
			(pts
				(xy -0.508 0.2794) (xy -0.508 0.2286) (xy -0.635 0.2286) (xy -0.635 -0.254) (xy -0.5334 -0.254)
				(xy -0.5334 -0.2794) (xy 0.5334 -0.2794) (xy 0.5334 -0.254) (xy 0.635 -0.254) (xy 0.635 0.254) (xy 0.5334 0.254)
				(xy 0.5334 0.2794)
			)
			(stroke
				(width 0)
				(type default)
			)
			(fill no)
			(layer "F.CrtYd")
		)
		(pad "1" smd rect
			(at 0.40005 0 270)
			(size 0.4572 0.508)
			(layers "F.Cu" "F.Mask" "F.Paste")
			(net "P3V3_STB_NODE1")
		)
		(pad "2" smd rect
			(at -0.40005 0 270)
			(size 0.4572 0.508)
			(layers "F.Cu" "F.Mask" "F.Paste")
			(net "SIO_PIN83")
		)
	)
	(footprint ""
		(layer "F.Cu")
		(at 118.376954 -24.064722 180)
		(property "Reference" "R1125"
			(at 0.435864 -2.038858 0)
			(unlocked yes)
			(layer "F.SilkS")
			(effects
				(font
					(size 0.7874 0.5842)
					(thickness 0.1524)
				)
				(justify left)
			)
		)
		(property "Value" ""
			(at 0 0 180)
			(layer "F.Fab")
			(effects
				(font
					(size 1.27 1.27)
				)
			)
		)
		(duplicate_pad_numbers_are_jumpers no)
		(fp_line
			(start 0.7874 0.4064)
			(end -0.7874 0.4064)
			(stroke
				(width 0.1524)
				(type default)
			)
			(layer "F.SilkS")
		)
		(fp_line
			(start 0.7874 -0.4064)
			(end 0.7874 0.4064)
			(stroke
				(width 0.1524)
				(type default)
			)
			(layer "F.SilkS")
		)
		(fp_line
			(start -0.7874 0.4064)
			(end -0.7874 -0.4064)
			(stroke
				(width 0.1524)
				(type default)
			)
			(layer "F.SilkS")
		)
		(fp_line
			(start -0.7874 -0.4064)
			(end 0.7874 -0.4064)
			(stroke
				(width 0.1524)
				(type default)
			)
			(layer "F.SilkS")
		)
		(fp_poly
			(pts
				(xy -0.508 0.2794) (xy -0.508 0.2286) (xy -0.635 0.2286) (xy -0.635 -0.254) (xy -0.5334 -0.254)
				(xy -0.5334 -0.2794) (xy 0.5334 -0.2794) (xy 0.5334 -0.254) (xy 0.635 -0.254) (xy 0.635 0.254) (xy 0.5334 0.254)
				(xy 0.5334 0.2794)
			)
			(stroke
				(width 0)
				(type default)
			)
			(fill no)
			(layer "F.CrtYd")
		)
		(pad "1" smd rect
			(at 0.40005 0 180)
			(size 0.4572 0.508)
			(layers "F.Cu" "F.Mask" "F.Paste")
			(net "PV_VTT_DDR_NODE1_REFIN")
		)
		(pad "2" smd rect
			(at -0.40005 0 180)
			(size 0.4572 0.508)
			(layers "F.Cu" "F.Mask" "F.Paste")
			(net "GND")
		)
	)
)
